# BASEBOARD_FAB2 (Tioga Pass) — schematic netlist excerpt (pin names and nets, part order shuffled) for the footprints in the layout excerpt that follows; sources: Cadence DE-HDL packaged netlist, KiCad conversion of Wiwynn_Tioga_Pass_MB.brd

C4G22  CAP_A  0.1UF 16V 10% X7R  pkg 0402V  page 99 : A = PVCCIO_CPU1 ; B = GND
C3U8  CAPP  470UF 2.5V 20% ALUM  pkg 3018  page 217 : A = PVDDQ_ABC ; B = GND

(kicad_pcb
	(version 20260206)
	(generator "pcbnew")
	(generator_version "10.0")
	(general
		(thickness 1.6)
		(legacy_teardrops no)
	)
	(paper "A4")
	(title_block
		(title "Wiwynn_Tioga_Pass_MB.brd")
		(comment 1 "Tioga Pass / footprints 3206-3207 of 4770")
	)
	(layers
		(0 "F.Cu" signal "TOP")
		(4 "In1.Cu" signal "L2GND")
		(6 "In2.Cu" signal "L3")
		(8 "In3.Cu" signal "L4GND")
		(10 "In4.Cu" signal "L5")
		(12 "In5.Cu" signal "L6GND")
		(14 "In6.Cu" signal "L7VCC")
		(16 "In7.Cu" signal "L8VCC")
		(18 "In8.Cu" signal "L9GND")
		(20 "In9.Cu" signal "L10")
		(22 "In10.Cu" signal "L11GND")
		(24 "In11.Cu" signal "L12")
		(26 "In12.Cu" signal "L13GND")
		(2 "B.Cu" signal "BOTTOM")
		(9 "F.Adhes" user "F.Adhesive")
		(11 "B.Adhes" user "B.Adhesive")
		(13 "F.Paste" user "Package Geometry/Pastemask Top")
		(15 "B.Paste" user "Package Geometry/Pastemask Bottom")
		(5 "F.SilkS" user "Ref Des/Silkscreen Top")
		(7 "B.SilkS" user "Ref Des/Silkscreen Bottom")
		(1 "F.Mask" user "Board Geometry/Soldermask Top")
		(3 "B.Mask" user "Board Geometry/Soldermask Bottom")
		(17 "Dwgs.User" user "User.Drawings")
		(19 "Cmts.User" user "User.Comments")
		(21 "Eco1.User" user "User.Eco1")
		(23 "Eco2.User" user "User.Eco2")
		(25 "Edge.Cuts" user "Board Geometry/Outline")
		(27 "Margin" user)
		(31 "F.CrtYd" user "Package Geometry/Place Bound Top")
		(29 "B.CrtYd" user "Package Geometry/Place Bound Bottom")
		(35 "F.Fab" user "Ref Des/Assembly Top")
		(33 "B.Fab" user "Ref Des/Assembly Bottom")
	)
	(footprint ""
		(layer "B.Cu")
		(at 334.01 2.032 90)
		(property "Reference" "C3U8"
			(at -3.07467 4.318 0)
			(unlocked yes)
			(layer "B.SilkS")
			(effects
				(font
					(size 0.7874 0.5842)
					(thickness 0.1524)
				)
				(justify mirror)
			)
		)
		(property "Value" ""
			(at 0 0 90)
			(layer "B.Fab")
			(effects
				(font
					(size 1.27 1.27)
				)
				(justify mirror)
			)
		)
		(duplicate_pad_numbers_are_jumpers no)
		(fp_line
			(start 2.563114 -1.616456)
			(end 2.563114 1.633728)
			(stroke
				(width 0.1524)
				(type default)
			)
			(layer "B.SilkS")
		)
		(fp_line
			(start 1.6002 -1.616456)
			(end 2.563114 -1.616456)
			(stroke
				(width 0.1524)
				(type default)
			)
			(layer "B.SilkS")
		)
		(fp_line
			(start -1.6002 -1.616456)
			(end -2.504948 -1.616456)
			(stroke
				(width 0.1524)
				(type default)
			)
			(layer "B.SilkS")
		)
		(fp_line
			(start -2.504948 -1.616456)
			(end -2.504948 1.633728)
			(stroke
				(width 0.1524)
				(type default)
			)
			(layer "B.SilkS")
		)
		(fp_line
			(start 2.563114 1.633728)
			(end 1.6002 1.633728)
			(stroke
				(width 0.1524)
				(type default)
			)
			(layer "B.SilkS")
		)
		(fp_line
			(start -2.504948 1.633728)
			(end -1.6002 1.633728)
			(stroke
				(width 0.1524)
				(type default)
			)
			(layer "B.SilkS")
		)
		(fp_line
			(start 2.286 7.366)
			(end 2.286 1.632712)
			(stroke
				(width 0.1524)
				(type default)
			)
			(layer "B.SilkS")
		)
		(fp_line
			(start 2.286 7.366)
			(end 1.60147 7.366)
			(stroke
				(width 0.1524)
				(type default)
			)
			(layer "B.SilkS")
		)
		(fp_line
			(start -2.286 7.366)
			(end -2.286 1.63195)
			(stroke
				(width 0.1524)
				(type default)
			)
			(layer "B.SilkS")
		)
		(fp_line
			(start -2.286 7.366)
			(end -1.600708 7.366)
			(stroke
				(width 0.1524)
				(type default)
			)
			(layer "B.SilkS")
		)
		(fp_rect
			(start -2.286 -0.254)
			(end 2.286 7.366)
			(stroke
				(width 0)
				(type default)
			)
			(fill no)
			(layer "B.CrtYd")
		)
		(fp_line
			(start 2.286 -0.254)
			(end -2.286 -0.254)
			(stroke
				(width 0.1)
				(type default)
			)
			(layer "B.Fab")
		)
		(fp_line
			(start -2.286 -0.254)
			(end -2.286 7.366)
			(stroke
				(width 0.1)
				(type default)
			)
			(layer "B.Fab")
		)
		(fp_line
			(start 2.286 7.366)
			(end 2.286 -0.254)
			(stroke
				(width 0.1)
				(type default)
			)
			(layer "B.Fab")
		)
		(fp_line
			(start -2.286 7.366)
			(end 2.286 7.366)
			(stroke
				(width 0.1)
				(type default)
			)
			(layer "B.Fab")
		)
		(pad "1" smd rect
			(at 0 0 270)
			(size 2.54 3.048)
			(layers "B.Cu" "B.Mask" "B.Paste")
			(net "PVDDQ_ABC")
		)
		(pad "2" smd rect
			(at 0 7.112 270)
			(size 2.54 3.048)
			(layers "B.Cu" "B.Mask" "B.Paste")
			(net "GND")
		)
	)
	(footprint ""
		(layer "B.Cu")
		(at 166.3192 1.2192 90)
		(property "Reference" "C4G22"
			(at 0 0 90)
			(layer "B.SilkS")
			(hide yes)
			(effects
				(font
					(size 1.27 1.27)
				)
				(justify mirror)
			)
		)
		(property "Value" ""
			(at 0 0 90)
			(layer "B.Fab")
			(effects
				(font
					(size 1.27 1.27)
				)
				(justify mirror)
			)
		)
		(duplicate_pad_numbers_are_jumpers no)
		(fp_poly
			(pts
				(xy -0.3048 -0.1016) (xy -0.3048 0.9906) (xy 0.3048 0.9906) (xy 0.3048 -0.1016)
			)
			(stroke
				(width 0)
				(type default)
			)
			(fill no)
			(layer "B.CrtYd")
		)
		(fp_line
			(start 0.3048 -0.1016)
			(end 0.3048 0.9906)
			(stroke
				(width 0.1)
				(type default)
			)
			(layer "B.Fab")
		)
		(fp_line
			(start -0.3048 -0.1016)
			(end 0.3048 -0.1016)
			(stroke
				(width 0.1)
				(type default)
			)
			(layer "B.Fab")
		)
		(fp_line
			(start 0.3048 0.9906)
			(end -0.3048 0.9906)
			(stroke
				(width 0.1)
				(type default)
			)
			(layer "B.Fab")
		)
		(fp_line
			(start -0.3048 0.9906)
			(end -0.3048 -0.1016)
			(stroke
				(width 0.1)
				(type default)
			)
			(layer "B.Fab")
		)
		(pad "1" smd rect
			(at 0 0 270)
			(size 0.508 0.508)
			(layers "B.Cu" "B.Mask" "B.Paste")
			(net "PVCCIO_CPU1")
		)
		(pad "2" smd rect
			(at 0 0.889 270)
			(size 0.508 0.508)
			(layers "B.Cu" "B.Mask" "B.Paste")
			(net "GND")
		)
		(zone
			(layer "B.Cu")
			(hatch none 0.5)
			(connect_pads
				(clearance 0)
			)
			(min_thickness 0.25)
			(keepout
				(tracks allowed)
				(vias not_allowed)
				(pads allowed)
				(copperpour not_allowed)
				(footprints allowed)
			)
			(placement
				(enabled no)
				(sheetname "")
			)
			(fill
				(thermal_gap 0.5)
				(thermal_bridge_width 0.5)
				(island_removal_mode 0)
			)
			(polygon
				(pts
					(xy 166.5732 0.9652) (xy 166.5732 1.4732) (xy 166.9542 1.4732) (xy 166.9542 0.9652)
				)
			)
		)
		(zone
			(layer "B.Cu")
			(hatch none 0.5)
			(connect_pads
				(clearance 0)
			)
			(min_thickness 0.25)
			(keepout
				(tracks not_allowed)
				(vias allowed)
				(pads allowed)
				(copperpour not_allowed)
				(footprints allowed)
			)
			(placement
				(enabled no)
				(sheetname "")
			)
			(fill
				(thermal_gap 0.5)
				(thermal_bridge_width 0.5)
				(island_removal_mode 0)
			)
			(polygon
				(pts
					(xy 166.9542 0.9652) (xy 166.9542 1.4732) (xy 166.5732 1.4732) (xy 166.5732 0.9652)
				)
			)
		)
	)
)
